(kicad_pcb
	(version 20260206)
	(generator "pcbnew")
	(generator_version "10.0")
	(general
		(thickness 1.6)
		(legacy_teardrops no)
	)
	(paper "A4")
	(title_block
		(title "9052_F0T_PDB_Converter_Brick_F_V03_1208_1600_OCP.brd")
		(comment 1 "Grand Teton / footprints 382-387 of 578")
	)
	(layers
		(0 "F.Cu" signal "TOP")
		(4 "In1.Cu" signal "GND")
		(6 "In2.Cu" signal "IN1")
		(8 "In3.Cu" signal "GND1")
		(10 "In4.Cu" signal "VCC")
		(12 "In5.Cu" signal "VCC1")
		(14 "In6.Cu" signal "GND2")
		(16 "In7.Cu" signal "IN2")
		(18 "In8.Cu" signal "GND3")
		(2 "B.Cu" signal "BOTTOM")
		(9 "F.Adhes" user "F.Adhesive")
		(11 "B.Adhes" user "B.Adhesive")
		(13 "F.Paste" user "Package Geometry/Pastemask Top")
		(15 "B.Paste" user "Package Geometry/Pastemask Bottom")
		(5 "F.SilkS" user "Ref Des/Silkscreen Top")
		(7 "B.SilkS" user "Ref Des/Silkscreen Bottom")
		(1 "F.Mask" user "Board Geometry/Soldermask Top")
		(3 "B.Mask" user "Board Geometry/Soldermask Bottom")
		(17 "Dwgs.User" user "User.Drawings")
		(19 "Cmts.User" user "User.Comments")
		(21 "Eco1.User" user "User.Eco1")
		(23 "Eco2.User" user "User.Eco2")
		(25 "Edge.Cuts" user "Board Geometry/Outline")
		(27 "Margin" user)
		(31 "F.CrtYd" user "Package Geometry/Place Bound Top")
		(29 "B.CrtYd" user "Package Geometry/Place Bound Bottom")
		(35 "F.Fab" user "Ref Des/Assembly Top")
		(33 "B.Fab" user "Ref Des/Assembly Bottom")
	)
	(footprint ""
		(layer "B.Cu")
		(at 232.537 -91.313 -90)
		(property "Reference" "R35"
			(at 0 0 90)
			(layer "B.SilkS")
			(hide yes)
			(effects
				(font
					(size 1.27 1.27)
				)
				(justify mirror)
			)
		)
		(property "Value" ""
			(at 0 0 90)
			(layer "B.Fab")
			(effects
				(font
					(size 1.27 1.27)
				)
				(justify mirror)
			)
		)
		(duplicate_pad_numbers_are_jumpers no)
		(fp_line
			(start -0.7874 0.4064)
			(end 0.7874 0.4064)
			(stroke
				(width 0.1524)
				(type default)
			)
			(layer "B.SilkS")
		)
		(fp_line
			(start 0.7874 0.4064)
			(end 0.7874 -0.4064)
			(stroke
				(width 0.1524)
				(type default)
			)
			(layer "B.SilkS")
		)
		(fp_line
			(start -0.7874 -0.4064)
			(end -0.7874 0.4064)
			(stroke
				(width 0.1524)
				(type default)
			)
			(layer "B.SilkS")
		)
		(fp_line
			(start 0.7874 -0.4064)
			(end -0.7874 -0.4064)
			(stroke
				(width 0.1524)
				(type default)
			)
			(layer "B.SilkS")
		)
		(fp_line
			(start -0.67945 0.3048)
			(end -0.120396 0.3048)
			(stroke
				(width 0.1)
				(type default)
			)
			(layer "B.Fab")
		)
		(fp_line
			(start -0.120396 0.3048)
			(end -0.120396 0.2794)
			(stroke
				(width 0.1)
				(type default)
			)
			(layer "B.Fab")
		)
		(fp_line
			(start 0.12065 0.3048)
			(end 0.67945 0.3048)
			(stroke
				(width 0.1)
				(type default)
			)
			(layer "B.Fab")
		)
		(fp_line
			(start 0.67945 0.3048)
			(end 0.67945 -0.305054)
			(stroke
				(width 0.1)
				(type default)
			)
			(layer "B.Fab")
		)
		(fp_line
			(start -0.120396 0.2794)
			(end 0.12065 0.2794)
			(stroke
				(width 0.1)
				(type default)
			)
			(layer "B.Fab")
		)
		(fp_line
			(start 0.12065 0.2794)
			(end 0.12065 0.3048)
			(stroke
				(width 0.1)
				(type default)
			)
			(layer "B.Fab")
		)
		(fp_line
			(start -0.12065 -0.2794)
			(end -0.12065 -0.3048)
			(stroke
				(width 0.1)
				(type default)
			)
			(layer "B.Fab")
		)
		(fp_line
			(start 0.12065 -0.2794)
			(end -0.12065 -0.2794)
			(stroke
				(width 0.1)
				(type default)
			)
			(layer "B.Fab")
		)
		(fp_line
			(start -0.67945 -0.3048)
			(end -0.67945 0.3048)
			(stroke
				(width 0.1)
				(type default)
			)
			(layer "B.Fab")
		)
		(fp_line
			(start -0.12065 -0.3048)
			(end -0.67945 -0.3048)
			(stroke
				(width 0.1)
				(type default)
			)
			(layer "B.Fab")
		)
		(fp_line
			(start 0.12065 -0.305054)
			(end 0.12065 -0.2794)
			(stroke
				(width 0.1)
				(type default)
			)
			(layer "B.Fab")
		)
		(fp_line
			(start 0.67945 -0.305054)
			(end 0.12065 -0.305054)
			(stroke
				(width 0.1)
				(type default)
			)
			(layer "B.Fab")
		)
		(pad "1" smd circle
			(at 0.40005 0 90)
			(size 0 0)
			(layers "B.Cu" "B.Mask" "B.Paste")
			(net "RST_SMB_PDB_BUF_R_N")
		)
		(pad "2" smd circle
			(at -0.40005 0 90)
			(size 0 0)
			(layers "B.Cu" "B.Mask" "B.Paste")
			(net "RST_SMB_PDB_BUF_N")
		)
	)
	(footprint ""
		(layer "B.Cu")
		(at 211.074 -67.183 90)
		(property "Reference" "R93"
			(at 0 0 90)
			(layer "B.SilkS")
			(hide yes)
			(effects
				(font
					(size 1.27 1.27)
				)
				(justify mirror)
			)
		)
		(property "Value" ""
			(at 0 0 90)
			(layer "B.Fab")
			(effects
				(font
					(size 1.27 1.27)
				)
				(justify mirror)
			)
		)
		(duplicate_pad_numbers_are_jumpers no)
		(fp_line
			(start 0.7874 -0.4064)
			(end -0.7874 -0.4064)
			(stroke
				(width 0.1524)
				(type default)
			)
			(layer "B.SilkS")
		)
		(fp_line
			(start -0.7874 -0.4064)
			(end -0.7874 0.4064)
			(stroke
				(width 0.1524)
				(type default)
			)
			(layer "B.SilkS")
		)
		(fp_line
			(start 0.7874 0.4064)
			(end 0.7874 -0.4064)
			(stroke
				(width 0.1524)
				(type default)
			)
			(layer "B.SilkS")
		)
		(fp_line
			(start -0.7874 0.4064)
			(end 0.7874 0.4064)
			(stroke
				(width 0.1524)
				(type default)
			)
			(layer "B.SilkS")
		)
		(fp_line
			(start 0.67945 -0.305054)
			(end 0.12065 -0.305054)
			(stroke
				(width 0.1)
				(type default)
			)
			(layer "B.Fab")
		)
		(fp_line
			(start 0.12065 -0.305054)
			(end 0.12065 -0.2794)
			(stroke
				(width 0.1)
				(type default)
			)
			(layer "B.Fab")
		)
		(fp_line
			(start -0.12065 -0.3048)
			(end -0.67945 -0.3048)
			(stroke
				(width 0.1)
				(type default)
			)
			(layer "B.Fab")
		)
		(fp_line
			(start -0.67945 -0.3048)
			(end -0.67945 0.3048)
			(stroke
				(width 0.1)
				(type default)
			)
			(layer "B.Fab")
		)
		(fp_line
			(start 0.12065 -0.2794)
			(end -0.12065 -0.2794)
			(stroke
				(width 0.1)
				(type default)
			)
			(layer "B.Fab")
		)
		(fp_line
			(start -0.12065 -0.2794)
			(end -0.12065 -0.3048)
			(stroke
				(width 0.1)
				(type default)
			)
			(layer "B.Fab")
		)
		(fp_line
			(start 0.12065 0.2794)
			(end 0.12065 0.3048)
			(stroke
				(width 0.1)
				(type default)
			)
			(layer "B.Fab")
		)
		(fp_line
			(start -0.120396 0.2794)
			(end 0.12065 0.2794)
			(stroke
				(width 0.1)
				(type default)
			)
			(layer "B.Fab")
		)
		(fp_line
			(start 0.67945 0.3048)
			(end 0.67945 -0.305054)
			(stroke
				(width 0.1)
				(type default)
			)
			(layer "B.Fab")
		)
		(fp_line
			(start 0.12065 0.3048)
			(end 0.67945 0.3048)
			(stroke
				(width 0.1)
				(type default)
			)
			(layer "B.Fab")
		)
		(fp_line
			(start -0.120396 0.3048)
			(end -0.120396 0.2794)
			(stroke
				(width 0.1)
				(type default)
			)
			(layer "B.Fab")
		)
		(fp_line
			(start -0.67945 0.3048)
			(end -0.120396 0.3048)
			(stroke
				(width 0.1)
				(type default)
			)
			(layer "B.Fab")
		)
		(pad "1" smd circle
			(at 0.40005 0 270)
			(size 0 0)
			(layers "B.Cu" "B.Mask" "B.Paste")
			(net "SKU_ID_2")
		)
		(pad "2" smd circle
			(at -0.40005 0 270)
			(size 0 0)
			(layers "B.Cu" "B.Mask" "B.Paste")
			(net "GND")
		)
	)
	(footprint ""
		(layer "B.Cu")
		(at 146.685 -110.109 180)
		(property "Reference" "R168"
			(at 0 0 0)
			(layer "B.SilkS")
			(hide yes)
			(effects
				(font
					(size 1.27 1.27)
				)
				(justify mirror)
			)
		)
		(property "Value" ""
			(at 0 0 0)
			(layer "B.Fab")
			(effects
				(font
					(size 1.27 1.27)
				)
				(justify mirror)
			)
		)
		(duplicate_pad_numbers_are_jumpers no)
		(fp_line
			(start 0.7874 0.4064)
			(end 0.7874 -0.4064)
			(stroke
				(width 0.1524)
				(type default)
			)
			(layer "B.SilkS")
		)
		(fp_line
			(start 0.7874 -0.4064)
			(end -0.7874 -0.4064)
			(stroke
				(width 0.1524)
				(type default)
			)
			(layer "B.SilkS")
		)
		(fp_line
			(start -0.7874 0.4064)
			(end 0.7874 0.4064)
			(stroke
				(width 0.1524)
				(type default)
			)
			(layer "B.SilkS")
		)
		(fp_line
			(start -0.7874 -0.4064)
			(end -0.7874 0.4064)
			(stroke
				(width 0.1524)
				(type default)
			)
			(layer "B.SilkS")
		)
		(fp_line
			(start 0.67945 0.3048)
			(end 0.67945 -0.305054)
			(stroke
				(width 0.1)
				(type default)
			)
			(layer "B.Fab")
		)
		(fp_line
			(start 0.67945 -0.305054)
			(end 0.12065 -0.305054)
			(stroke
				(width 0.1)
				(type default)
			)
			(layer "B.Fab")
		)
		(fp_line
			(start 0.12065 0.3048)
			(end 0.67945 0.3048)
			(stroke
				(width 0.1)
				(type default)
			)
			(layer "B.Fab")
		)
		(fp_line
			(start 0.12065 0.2794)
			(end 0.12065 0.3048)
			(stroke
				(width 0.1)
				(type default)
			)
			(layer "B.Fab")
		)
		(fp_line
			(start 0.12065 -0.2794)
			(end -0.12065 -0.2794)
			(stroke
				(width 0.1)
				(type default)
			)
			(layer "B.Fab")
		)
		(fp_line
			(start 0.12065 -0.305054)
			(end 0.12065 -0.2794)
			(stroke
				(width 0.1)
				(type default)
			)
			(layer "B.Fab")
		)
		(fp_line
			(start -0.120396 0.3048)
			(end -0.120396 0.2794)
			(stroke
				(width 0.1)
				(type default)
			)
			(layer "B.Fab")
		)
		(fp_line
			(start -0.120396 0.2794)
			(end 0.12065 0.2794)
			(stroke
				(width 0.1)
				(type default)
			)
			(layer "B.Fab")
		)
		(fp_line
			(start -0.12065 -0.2794)
			(end -0.12065 -0.3048)
			(stroke
				(width 0.1)
				(type default)
			)
			(layer "B.Fab")
		)
		(fp_line
			(start -0.12065 -0.3048)
			(end -0.67945 -0.3048)
			(stroke
				(width 0.1)
				(type default)
			)
			(layer "B.Fab")
		)
		(fp_line
			(start -0.67945 0.3048)
			(end -0.120396 0.3048)
			(stroke
				(width 0.1)
				(type default)
			)
			(layer "B.Fab")
		)
		(fp_line
			(start -0.67945 -0.3048)
			(end -0.67945 0.3048)
			(stroke
				(width 0.1)
				(type default)
			)
			(layer "B.Fab")
		)
		(pad "1" smd circle
			(at 0.40005 0)
			(size 0 0)
			(layers "B.Cu" "B.Mask" "B.Paste")
			(net "P3V3_AUX")
		)
		(pad "2" smd circle
			(at -0.40005 0)
			(size 0 0)
			(layers "B.Cu" "B.Mask" "B.Paste")
			(net "BRICK_P12V0_EN_R_N")
		)
	)
	(footprint ""
		(layer "B.Cu")
		(at 240.538 -75.819 90)
		(property "Reference" "R74"
			(at 0 0 90)
			(layer "B.SilkS")
			(hide yes)
			(effects
				(font
					(size 1.27 1.27)
				)
				(justify mirror)
			)
		)
		(property "Value" ""
			(at 0 0 90)
			(layer "B.Fab")
			(effects
				(font
					(size 1.27 1.27)
				)
				(justify mirror)
			)
		)
		(duplicate_pad_numbers_are_jumpers no)
		(fp_line
			(start 0.7874 -0.4064)
			(end -0.7874 -0.4064)
			(stroke
				(width 0.1524)
				(type default)
			)
			(layer "B.SilkS")
		)
		(fp_line
			(start -0.7874 -0.4064)
			(end -0.7874 0.4064)
			(stroke
				(width 0.1524)
				(type default)
			)
			(layer "B.SilkS")
		)
		(fp_line
			(start 0.7874 0.4064)
			(end 0.7874 -0.4064)
			(stroke
				(width 0.1524)
				(type default)
			)
			(layer "B.SilkS")
		)
		(fp_line
			(start -0.7874 0.4064)
			(end 0.7874 0.4064)
			(stroke
				(width 0.1524)
				(type default)
			)
			(layer "B.SilkS")
		)
		(fp_line
			(start 0.67945 -0.305054)
			(end 0.12065 -0.305054)
			(stroke
				(width 0.1)
				(type default)
			)
			(layer "B.Fab")
		)
		(fp_line
			(start 0.12065 -0.305054)
			(end 0.12065 -0.2794)
			(stroke
				(width 0.1)
				(type default)
			)
			(layer "B.Fab")
		)
		(fp_line
			(start -0.12065 -0.3048)
			(end -0.67945 -0.3048)
			(stroke
				(width 0.1)
				(type default)
			)
			(layer "B.Fab")
		)
		(fp_line
			(start -0.67945 -0.3048)
			(end -0.67945 0.3048)
			(stroke
				(width 0.1)
				(type default)
			)
			(layer "B.Fab")
		)
		(fp_line
			(start 0.12065 -0.2794)
			(end -0.12065 -0.2794)
			(stroke
				(width 0.1)
				(type default)
			)
			(layer "B.Fab")
		)
		(fp_line
			(start -0.12065 -0.2794)
			(end -0.12065 -0.3048)
			(stroke
				(width 0.1)
				(type default)
			)
			(layer "B.Fab")
		)
		(fp_line
			(start 0.12065 0.2794)
			(end 0.12065 0.3048)
			(stroke
				(width 0.1)
				(type default)
			)
			(layer "B.Fab")
		)
		(fp_line
			(start -0.120396 0.2794)
			(end 0.12065 0.2794)
			(stroke
				(width 0.1)
				(type default)
			)
			(layer "B.Fab")
		)
		(fp_line
			(start 0.67945 0.3048)
			(end 0.67945 -0.305054)
			(stroke
				(width 0.1)
				(type default)
			)
			(layer "B.Fab")
		)
		(fp_line
			(start 0.12065 0.3048)
			(end 0.67945 0.3048)
			(stroke
				(width 0.1)
				(type default)
			)
			(layer "B.Fab")
		)
		(fp_line
			(start -0.120396 0.3048)
			(end -0.120396 0.2794)
			(stroke
				(width 0.1)
				(type default)
			)
			(layer "B.Fab")
		)
		(fp_line
			(start -0.67945 0.3048)
			(end -0.120396 0.3048)
			(stroke
				(width 0.1)
				(type default)
			)
			(layer "B.Fab")
		)
		(pad "1" smd circle
			(at 0.40005 0 270)
			(size 0 0)
			(layers "B.Cu" "B.Mask" "B.Paste")
			(net "P3V3_AUX")
		)
		(pad "2" smd circle
			(at -0.40005 0 270)
			(size 0 0)
			(layers "B.Cu" "B.Mask" "B.Paste")
			(net "SMB_MB_PDB_R_SCL")
		)
	)
	(footprint ""
		(layer "B.Cu")
		(at 291.592 -53.34 90)
		(property "Reference" "PR2"
			(at 0 0 90)
			(layer "B.SilkS")
			(hide yes)
			(effects
				(font
					(size 1.27 1.27)
				)
				(justify mirror)
			)
		)
		(property "Value" ""
			(at 0 0 90)
			(layer "B.Fab")
			(effects
				(font
					(size 1.27 1.27)
				)
				(justify mirror)
			)
		)
		(duplicate_pad_numbers_are_jumpers no)
		(fp_line
			(start 1.651 -0.8382)
			(end -1.651 -0.8382)
			(stroke
				(width 0.1524)
				(type default)
			)
			(layer "B.SilkS")
		)
		(fp_line
			(start -1.651 -0.8382)
			(end -1.651 0.8382)
			(stroke
				(width 0.1524)
				(type default)
			)
			(layer "B.SilkS")
		)
		(fp_line
			(start 1.651 0.8382)
			(end 1.651 -0.8382)
			(stroke
				(width 0.1524)
				(type default)
			)
			(layer "B.SilkS")
		)
		(fp_line
			(start -1.651 0.8382)
			(end 1.651 0.8382)
			(stroke
				(width 0.1524)
				(type default)
			)
			(layer "B.SilkS")
		)
		(fp_line
			(start 1.559814 -0.7366)
			(end 1.559814 0.7366)
			(stroke
				(width 0.1)
				(type default)
			)
			(layer "B.Fab")
		)
		(fp_line
			(start 1.524 -0.7366)
			(end 1.559814 -0.7366)
			(stroke
				(width 0.1)
				(type default)
			)
			(layer "B.Fab")
		)
		(fp_line
			(start -1.524 -0.7366)
			(end 1.524 -0.7366)
			(stroke
				(width 0.1)
				(type default)
			)
			(layer "B.Fab")
		)
		(fp_line
			(start -1.560576 -0.7366)
			(end -1.524 -0.7366)
			(stroke
				(width 0.1)
				(type default)
			)
			(layer "B.Fab")
		)
		(fp_line
			(start 1.559814 0.7366)
			(end 1.524 0.7366)
			(stroke
				(width 0.1)
				(type default)
			)
			(layer "B.Fab")
		)
		(fp_line
			(start 1.524 0.7366)
			(end -1.524 0.7366)
			(stroke
				(width 0.1)
				(type default)
			)
			(layer "B.Fab")
		)
		(fp_line
			(start -1.524 0.7366)
			(end -1.560576 0.7366)
			(stroke
				(width 0.1)
				(type default)
			)
			(layer "B.Fab")
		)
		(fp_line
			(start -1.560576 0.7366)
			(end -1.560576 -0.7366)
			(stroke
				(width 0.1)
				(type default)
			)
			(layer "B.Fab")
		)
		(pad "1" smd rect
			(at 0.94996 0 90)
			(size 1.1176 1.3716)
			(layers "B.Cu" "B.Mask" "B.Paste")
			(net "P52V_1")
		)
		(pad "2" smd rect
			(at -0.94996 0 90)
			(size 1.1176 1.3716)
			(layers "B.Cu" "B.Mask" "B.Paste")
			(net "P52V_HS1_OV")
		)
	)
	(footprint ""
		(layer "B.Cu")
		(at 106.684826 -110.109 180)
		(property "Reference" "R201"
			(at 0 0 0)
			(layer "B.SilkS")
			(hide yes)
			(effects
				(font
					(size 1.27 1.27)
				)
				(justify mirror)
			)
		)
		(property "Value" ""
			(at 0 0 0)
			(layer "B.Fab")
			(effects
				(font
					(size 1.27 1.27)
				)
				(justify mirror)
			)
		)
		(duplicate_pad_numbers_are_jumpers no)
		(fp_line
			(start 0.7874 0.4064)
			(end 0.7874 -0.4064)
			(stroke
				(width 0.1524)
				(type default)
			)
			(layer "B.SilkS")
		)
		(fp_line
			(start 0.7874 -0.4064)
			(end -0.7874 -0.4064)
			(stroke
				(width 0.1524)
				(type default)
			)
			(layer "B.SilkS")
		)
		(fp_line
			(start -0.7874 0.4064)
			(end 0.7874 0.4064)
			(stroke
				(width 0.1524)
				(type default)
			)
			(layer "B.SilkS")
		)
		(fp_line
			(start -0.7874 -0.4064)
			(end -0.7874 0.4064)
			(stroke
				(width 0.1524)
				(type default)
			)
			(layer "B.SilkS")
		)
		(fp_line
			(start 0.67945 0.3048)
			(end 0.67945 -0.305054)
			(stroke
				(width 0.1)
				(type default)
			)
			(layer "B.Fab")
		)
		(fp_line
			(start 0.67945 -0.305054)
			(end 0.12065 -0.305054)
			(stroke
				(width 0.1)
				(type default)
			)
			(layer "B.Fab")
		)
		(fp_line
			(start 0.12065 0.3048)
			(end 0.67945 0.3048)
			(stroke
				(width 0.1)
				(type default)
			)
			(layer "B.Fab")
		)
		(fp_line
			(start 0.12065 0.2794)
			(end 0.12065 0.3048)
			(stroke
				(width 0.1)
				(type default)
			)
			(layer "B.Fab")
		)
		(fp_line
			(start 0.12065 -0.2794)
			(end -0.12065 -0.2794)
			(stroke
				(width 0.1)
				(type default)
			)
			(layer "B.Fab")
		)
		(fp_line
			(start 0.12065 -0.305054)
			(end 0.12065 -0.2794)
			(stroke
				(width 0.1)
				(type default)
			)
			(layer "B.Fab")
		)
		(fp_line
			(start -0.120396 0.3048)
			(end -0.120396 0.2794)
			(stroke
				(width 0.1)
				(type default)
			)
			(layer "B.Fab")
		)
		(fp_line
			(start -0.120396 0.2794)
			(end 0.12065 0.2794)
			(stroke
				(width 0.1)
				(type default)
			)
			(layer "B.Fab")
		)
		(fp_line
			(start -0.12065 -0.2794)
			(end -0.12065 -0.3048)
			(stroke
				(width 0.1)
				(type default)
			)
			(layer "B.Fab")
		)
		(fp_line
			(start -0.12065 -0.3048)
			(end -0.67945 -0.3048)
			(stroke
				(width 0.1)
				(type default)
			)
			(layer "B.Fab")
		)
		(fp_line
			(start -0.67945 0.3048)
			(end -0.120396 0.3048)
			(stroke
				(width 0.1)
				(type default)
			)
			(layer "B.Fab")
		)
		(fp_line
			(start -0.67945 -0.3048)
			(end -0.67945 0.3048)
			(stroke
				(width 0.1)
				(type default)
			)
			(layer "B.Fab")
		)
		(pad "1" smd circle
			(at 0.40005 0)
			(size 0 0)
			(layers "B.Cu" "B.Mask" "B.Paste")
			(net "P3V3_AUX")
		)
		(pad "2" smd circle
			(at -0.40005 0)
			(size 0 0)
			(layers "B.Cu" "B.Mask" "B.Paste")
			(net "BRICK_P12V_EN_R_N")
		)
	)
)
